FILE_TYPE = MACRO_DRAWING;
SET COLOR_WIRE YELLOW;
SET COLOR_PROP MONO;
SET COLOR_DOT WHITE;
SET COLOR_ARC YELLOW;
SET COLOR_BODY GREEN;
SET COLOR_NOTE MONO;
SET PROP_DISPLAY VALUE;
SET PAGE_NUMBER P178;
FORCEADD RES..1
(-800 3725);
FORCEPROP 1 LAST LOCATION R8D20
J 0
(-825 3775);
DISPLAY 0.617021 (-825 3775);
PAINT AQUA (-825 3775);
FORCEPROP 1 LAST PART_NUMBER G21796-047
J 0
(-525 3675);
DISPLAY 0.617021 (-525 3675);
PAINT BLUE (-525 3675);
FORCEPROP 1 LAST VALUE 49.9
J 2
(-825 3675);
DISPLAY 0.617021 (-825 3675);
PAINT SKYBLUE (-825 3675);
FORCEPROP 1 LAST TOLERANCE 1%
J 0
(-800 3675);
DISPLAY 0.617021 (-800 3675);
PAINT SKYBLUE (-800 3675);
FORCEPROP 1 LAST PACK_TYPE 0402
J 0
(-625 3675);
DISPLAY 0.617021 (-625 3675);
PAINT SKYBLUE (-625 3675);
FORCEPROP 1 LAST MATERIAL CHIP
J 0
(-725 3675);
DISPLAY 0.617021 (-725 3675);
PAINT SKYBLUE (-725 3675);
FORCEPROP 1 LAST WATTAGE 1/16W
J 2
(-925 3675);
DISPLAY 0.617021 (-925 3675);
PAINT SKYBLUE (-925 3675);
FORCEPROP 1 LASTPIN (-700 3725) $PN 2
J 0
(-738 3737);
DISPLAY 0.617021 (-738 3737);
PAINT ORANGE (-738 3737);
FORCEPROP 1 LASTPIN (-900 3725) $PN 1
J 0
(-888 3737);
DISPLAY 0.617021 (-888 3737);
PAINT ORANGE (-888 3737);
FORCEPROP 2 LAST CDS_LIB mstr_discrete
J 0
(-800 3725);
PAINT MONO (-800 3725);
DISPLAY INVISIBLE (-800 3725);
FORCEPROP 2 LAST SEC_TYPE 0402
J 0
(-850 3925);
DISPLAY 1.021277 (-850 3925);
PAINT ORANGE (-850 3925);
DISPLAY INVISIBLE (-850 3925);
FORCEPROP 0 LAST BOM_COST ST_SATA
J 0
(-800 3925);
DISPLAY 1.021277 (-800 3925);
PAINT ORANGE (-800 3925);
DISPLAY INVISIBLE (-800 3925);
FORCEPROP 2 LAST SEC 1
J 0
(-850 3925);
DISPLAY 0.680851 (-850 3925);
PAINT MONO (-850 3925);
DISPLAY INVISIBLE (-850 3925);
FORCEPROP 2 LAST CDS_LOCATION R8D20
J 0
(-825 3775);
DISPLAY 0.617021 (-825 3775);
PAINT AQUA (-825 3775);
DISPLAY INVISIBLE (-825 3775);
FORCEPROP 1 LAST PATH I1
J 0
(-850 3875);
DISPLAY 0.978723 (-850 3875);
PAINT WHITE (-850 3875);
DISPLAY INVISIBLE (-850 3875);
FORCEPROP 0 LAST ROOM ST_SATA
J 0
(-850 3925);
DISPLAY 1.021277 (-850 3925);
PAINT ORANGE (-850 3925);
DISPLAY INVISIBLE (-850 3925);
FORCEADD OFFPAGE..2
(1450 3425);
FORCEPROP 2 LAST $XR0 173 
J 0
(1639 3425);
DISPLAY 0.638298 (1639 3425);
PAINT MONO (1639 3425);
FORCEPROP 2 LAST CDS_LIB mstr_standard
J 0
(1450 3425);
PAINT MONO (1450 3425);
DISPLAY INVISIBLE (1450 3425);
FORCEPROP 1 LAST OFFPAGE TRUE
J 0
(1775 3300);
DISPLAY 0.872340 (1775 3300);
PAINT GREEN (1775 3300);
DISPLAY INVISIBLE (1775 3300);
FORCEPROP 1 LAST COMMENT_BODY TRUE
J 0
(1405 3330);
DISPLAY 0.872340 (1405 3330);
PAINT GREEN (1405 3330);
DISPLAY INVISIBLE (1405 3330);
FORCEPROP 2 LAST PATH I10
J 0
(1625 3500);
DISPLAY 1.021277 (1625 3500);
PAINT ORANGE (1625 3500);
DISPLAY INVISIBLE (1625 3500);
FORCEADD RES..1
(-800 3425);
FORCEPROP 1 LAST LOCATION R2N31
J 0
(-825 3475);
DISPLAY 0.617021 (-825 3475);
PAINT AQUA (-825 3475);
FORCEPROP 1 LAST PART_NUMBER G21796-047
J 0
(-525 3375);
DISPLAY 0.617021 (-525 3375);
PAINT BLUE (-525 3375);
FORCEPROP 1 LAST VALUE 49.9
J 2
(-825 3375);
DISPLAY 0.617021 (-825 3375);
PAINT SKYBLUE (-825 3375);
FORCEPROP 1 LAST TOLERANCE 1%
J 0
(-800 3375);
DISPLAY 0.617021 (-800 3375);
PAINT SKYBLUE (-800 3375);
FORCEPROP 1 LAST PACK_TYPE 0402
J 0
(-625 3375);
DISPLAY 0.617021 (-625 3375);
PAINT SKYBLUE (-625 3375);
FORCEPROP 1 LAST MATERIAL CHIP
J 0
(-725 3375);
DISPLAY 0.617021 (-725 3375);
PAINT SKYBLUE (-725 3375);
FORCEPROP 1 LAST WATTAGE 1/16W
J 2
(-925 3375);
DISPLAY 0.617021 (-925 3375);
PAINT SKYBLUE (-925 3375);
FORCEPROP 1 LASTPIN (-700 3425) $PN 2
J 0
(-738 3437);
DISPLAY 0.617021 (-738 3437);
PAINT ORANGE (-738 3437);
FORCEPROP 1 LASTPIN (-900 3425) $PN 1
J 0
(-888 3437);
DISPLAY 0.617021 (-888 3437);
PAINT ORANGE (-888 3437);
FORCEPROP 2 LAST CDS_LIB mstr_discrete
J 0
(-800 3425);
PAINT MONO (-800 3425);
DISPLAY INVISIBLE (-800 3425);
FORCEPROP 2 LAST SEC_TYPE 0402
J 0
(-850 3625);
DISPLAY 1.021277 (-850 3625);
PAINT ORANGE (-850 3625);
DISPLAY INVISIBLE (-850 3625);
FORCEPROP 0 LAST BOM_COST ST_SATA
J 0
(-800 3625);
DISPLAY 1.021277 (-800 3625);
PAINT ORANGE (-800 3625);
DISPLAY INVISIBLE (-800 3625);
FORCEPROP 2 LAST SEC 1
J 0
(-850 3625);
DISPLAY 0.680851 (-850 3625);
PAINT MONO (-850 3625);
DISPLAY INVISIBLE (-850 3625);
FORCEPROP 1 LAST PATH I11
J 0
(-850 3575);
DISPLAY 0.978723 (-850 3575);
PAINT WHITE (-850 3575);
DISPLAY INVISIBLE (-850 3575);
FORCEPROP 0 LAST ROOM ST_SATA
J 0
(-850 3625);
DISPLAY 1.021277 (-850 3625);
PAINT ORANGE (-850 3625);
DISPLAY INVISIBLE (-850 3625);
FORCEADD RES..2
R 2
(225 4125);
FORCEPROP 1 LAST LOCATION R2L15
J 2
(180 4250);
DISPLAY 0.617021 (180 4250);
PAINT AQUA (180 4250);
FORCEPROP 1 LAST PART_NUMBER G21796-001
J 2
(185 4000);
DISPLAY 0.617021 (185 4000);
PAINT BLUE (185 4000);
FORCEPROP 1 LAST VALUE 2.0K
J 2
(180 4200);
DISPLAY 0.617021 (180 4200);
PAINT SKYBLUE (180 4200);
FORCEPROP 1 LAST TOLERANCE 1%
J 2
(180 4150);
DISPLAY 0.617021 (180 4150);
PAINT SKYBLUE (180 4150);
FORCEPROP 1 LAST PACK_TYPE 0402
J 2
(185 3950);
DISPLAY 0.617021 (185 3950);
PAINT SKYBLUE (185 3950);
FORCEPROP 1 LAST MATERIAL CHIP
J 2
(185 4050);
DISPLAY 0.617021 (185 4050);
PAINT SKYBLUE (185 4050);
FORCEPROP 1 LAST WATTAGE 1/16W
J 2
(185 4100);
DISPLAY 0.617021 (185 4100);
PAINT SKYBLUE (185 4100);
FORCEPROP 1 LASTPIN (225 4025) $PN 2
J 2
(220 4035);
DISPLAY 0.617021 (220 4035);
PAINT ORANGE (220 4035);
FORCEPROP 1 LASTPIN (225 4225) $PN 1
J 2
(220 4187);
DISPLAY 0.617021 (220 4187);
PAINT ORANGE (220 4187);
FORCEPROP 2 LAST CDS_LIB mstr_discrete
J 0
(225 4125);
PAINT MONO (225 4125);
DISPLAY INVISIBLE (225 4125);
FORCEPROP 2 LAST SEC_TYPE 0402
J 0
(175 4350);
DISPLAY 1.021277 (175 4350);
PAINT ORANGE (175 4350);
DISPLAY INVISIBLE (175 4350);
FORCEPROP 0 LAST BOM_COST ST_SATA
J 0
(200 4350);
DISPLAY 1.021277 (200 4350);
PAINT ORANGE (200 4350);
DISPLAY INVISIBLE (200 4350);
FORCEPROP 2 LAST SEC 1
J 0
(175 4350);
DISPLAY 0.680851 (175 4350);
PAINT MONO (175 4350);
DISPLAY INVISIBLE (175 4350);
FORCEPROP 2 LAST CDS_LOCATION R2L15
J 2
(180 4250);
DISPLAY 0.617021 (180 4250);
PAINT AQUA (180 4250);
DISPLAY INVISIBLE (180 4250);
FORCEPROP 1 LAST PATH I12
J 2
(175 4300);
DISPLAY 0.978723 (175 4300);
PAINT WHITE (175 4300);
DISPLAY INVISIBLE (175 4300);
FORCEPROP 0 LAST ROOM ST_SATA
J 0
(200 4350);
DISPLAY 1.021277 (200 4350);
PAINT ORANGE (200 4350);
DISPLAY INVISIBLE (200 4350);
FORCEADD RES..2
R 2
(575 4125);
FORCEPROP 1 LAST LOCATION R2L11
J 2
(530 4250);
DISPLAY 0.617021 (530 4250);
PAINT AQUA (530 4250);
FORCEPROP 1 LAST PART_NUMBER G21796-001
J 2
(535 4000);
DISPLAY 0.617021 (535 4000);
PAINT BLUE (535 4000);
FORCEPROP 1 LAST VALUE 2.0K
J 2
(530 4200);
DISPLAY 0.617021 (530 4200);
PAINT SKYBLUE (530 4200);
FORCEPROP 1 LAST TOLERANCE 1%
J 2
(530 4150);
DISPLAY 0.617021 (530 4150);
PAINT SKYBLUE (530 4150);
FORCEPROP 1 LAST PACK_TYPE 0402
J 2
(535 3950);
DISPLAY 0.617021 (535 3950);
PAINT SKYBLUE (535 3950);
FORCEPROP 1 LAST MATERIAL CHIP
J 2
(535 4050);
DISPLAY 0.617021 (535 4050);
PAINT SKYBLUE (535 4050);
FORCEPROP 1 LAST WATTAGE 1/16W
J 2
(535 4100);
DISPLAY 0.617021 (535 4100);
PAINT SKYBLUE (535 4100);
FORCEPROP 1 LASTPIN (575 4025) $PN 2
J 2
(570 4035);
DISPLAY 0.617021 (570 4035);
PAINT ORANGE (570 4035);
FORCEPROP 1 LASTPIN (575 4225) $PN 1
J 2
(570 4187);
DISPLAY 0.617021 (570 4187);
PAINT ORANGE (570 4187);
FORCEPROP 2 LAST CDS_LIB mstr_discrete
J 0
(575 4125);
PAINT MONO (575 4125);
DISPLAY INVISIBLE (575 4125);
FORCEPROP 2 LAST SEC_TYPE 0402
J 0
(525 4350);
DISPLAY 1.021277 (525 4350);
PAINT ORANGE (525 4350);
DISPLAY INVISIBLE (525 4350);
FORCEPROP 0 LAST BOM_COST ST_SATA
J 0
(550 4350);
DISPLAY 1.021277 (550 4350);
PAINT ORANGE (550 4350);
DISPLAY INVISIBLE (550 4350);
FORCEPROP 2 LAST SEC 1
J 0
(525 4350);
DISPLAY 0.680851 (525 4350);
PAINT MONO (525 4350);
DISPLAY INVISIBLE (525 4350);
FORCEPROP 2 LAST CDS_LOCATION R2L11
J 2
(530 4250);
DISPLAY 0.617021 (530 4250);
PAINT AQUA (530 4250);
DISPLAY INVISIBLE (530 4250);
FORCEPROP 1 LAST PATH I13
J 2
(525 4300);
DISPLAY 0.978723 (525 4300);
PAINT WHITE (525 4300);
DISPLAY INVISIBLE (525 4300);
FORCEPROP 0 LAST ROOM ST_SATA
J 0
(550 4350);
DISPLAY 1.021277 (550 4350);
PAINT ORANGE (550 4350);
DISPLAY INVISIBLE (550 4350);
FORCEADD OFFPAGE..2
(1450 1825);
FORCEPROP 2 LAST $XR0 174 
J 0
(1639 1825);
DISPLAY 0.638298 (1639 1825);
PAINT MONO (1639 1825);
FORCEPROP 2 LAST CDS_LIB mstr_standard
J 0
(1450 1825);
PAINT MONO (1450 1825);
DISPLAY INVISIBLE (1450 1825);
FORCEPROP 1 LAST OFFPAGE TRUE
J 0
(1775 1700);
DISPLAY 0.872340 (1775 1700);
PAINT GREEN (1775 1700);
DISPLAY INVISIBLE (1775 1700);
FORCEPROP 1 LAST COMMENT_BODY TRUE
J 0
(1405 1730);
DISPLAY 0.872340 (1405 1730);
PAINT GREEN (1405 1730);
DISPLAY INVISIBLE (1405 1730);
FORCEPROP 2 LAST PATH I14
J 0
(1625 1900);
DISPLAY 1.021277 (1625 1900);
PAINT ORANGE (1625 1900);
DISPLAY INVISIBLE (1625 1900);
FORCEADD OFFPAGE..2
(1450 1675);
FORCEPROP 2 LAST $XR0 174 
J 0
(1639 1675);
DISPLAY 0.638298 (1639 1675);
PAINT MONO (1639 1675);
FORCEPROP 2 LAST CDS_LIB mstr_standard
J 0
(1450 1675);
PAINT MONO (1450 1675);
DISPLAY INVISIBLE (1450 1675);
FORCEPROP 1 LAST OFFPAGE TRUE
J 0
(1775 1550);
DISPLAY 0.872340 (1775 1550);
PAINT GREEN (1775 1550);
DISPLAY INVISIBLE (1775 1550);
FORCEPROP 1 LAST COMMENT_BODY TRUE
J 0
(1405 1580);
DISPLAY 0.872340 (1405 1580);
PAINT GREEN (1405 1580);
DISPLAY INVISIBLE (1405 1580);
FORCEPROP 2 LAST PATH I15
J 0
(1625 1750);
DISPLAY 1.021277 (1625 1750);
PAINT ORANGE (1625 1750);
DISPLAY INVISIBLE (1625 1750);
FORCEADD OFFPAGE..2
(1450 1525);
FORCEPROP 2 LAST $XR0 174 
J 0
(1639 1525);
DISPLAY 0.638298 (1639 1525);
PAINT MONO (1639 1525);
FORCEPROP 2 LAST CDS_LIB mstr_standard
J 0
(1450 1525);
PAINT MONO (1450 1525);
DISPLAY INVISIBLE (1450 1525);
FORCEPROP 1 LAST OFFPAGE TRUE
J 0
(1775 1400);
DISPLAY 0.872340 (1775 1400);
PAINT GREEN (1775 1400);
DISPLAY INVISIBLE (1775 1400);
FORCEPROP 1 LAST COMMENT_BODY TRUE
J 0
(1405 1430);
DISPLAY 0.872340 (1405 1430);
PAINT GREEN (1405 1430);
DISPLAY INVISIBLE (1405 1430);
FORCEPROP 2 LAST PATH I16
J 0
(1625 1600);
DISPLAY 1.021277 (1625 1600);
PAINT ORANGE (1625 1600);
DISPLAY INVISIBLE (1625 1600);
FORCEADD RES..2
R 2
(475 2225);
FORCEPROP 1 LAST LOCATION R2L6
J 2
(430 2350);
DISPLAY 0.617021 (430 2350);
PAINT AQUA (430 2350);
FORCEPROP 1 LAST PART_NUMBER G21796-001
J 2
(435 2100);
DISPLAY 0.617021 (435 2100);
PAINT BLUE (435 2100);
FORCEPROP 1 LAST VALUE 2.0K
J 2
(430 2300);
DISPLAY 0.617021 (430 2300);
PAINT SKYBLUE (430 2300);
FORCEPROP 1 LAST TOLERANCE 1%
J 2
(430 2250);
DISPLAY 0.617021 (430 2250);
PAINT SKYBLUE (430 2250);
FORCEPROP 1 LAST PACK_TYPE 0402
J 2
(435 2050);
DISPLAY 0.617021 (435 2050);
PAINT SKYBLUE (435 2050);
FORCEPROP 1 LAST MATERIAL CHIP
J 2
(435 2150);
DISPLAY 0.617021 (435 2150);
PAINT SKYBLUE (435 2150);
FORCEPROP 1 LAST WATTAGE 1/16W
J 2
(435 2200);
DISPLAY 0.617021 (435 2200);
PAINT SKYBLUE (435 2200);
FORCEPROP 1 LASTPIN (475 2125) $PN 2
J 2
(470 2135);
DISPLAY 0.617021 (470 2135);
PAINT ORANGE (470 2135);
FORCEPROP 1 LASTPIN (475 2325) $PN 1
J 2
(470 2287);
DISPLAY 0.617021 (470 2287);
PAINT ORANGE (470 2287);
FORCEPROP 0 LAST BOM_COST ST_SATA
J 0
(450 2450);
DISPLAY 1.021277 (450 2450);
PAINT ORANGE (450 2450);
DISPLAY INVISIBLE (450 2450);
FORCEPROP 2 LAST SEC_TYPE 0402
J 0
(425 2450);
DISPLAY 1.021277 (425 2450);
PAINT ORANGE (425 2450);
DISPLAY INVISIBLE (425 2450);
FORCEPROP 2 LAST CDS_LIB mstr_discrete
J 0
(475 2225);
PAINT MONO (475 2225);
DISPLAY INVISIBLE (475 2225);
FORCEPROP 2 LAST SEC 1
J 0
(425 2450);
DISPLAY 0.680851 (425 2450);
PAINT MONO (425 2450);
DISPLAY INVISIBLE (425 2450);
FORCEPROP 2 LAST CDS_LOCATION R2L6
J 2
(430 2350);
DISPLAY 0.617021 (430 2350);
PAINT AQUA (430 2350);
DISPLAY INVISIBLE (430 2350);
FORCEPROP 1 LAST PATH I17
J 2
(425 2400);
DISPLAY 0.978723 (425 2400);
PAINT WHITE (425 2400);
DISPLAY INVISIBLE (425 2400);
FORCEPROP 0 LAST ROOM ST_SATA
J 0
(450 2450);
DISPLAY 1.021277 (450 2450);
PAINT ORANGE (450 2450);
DISPLAY INVISIBLE (450 2450);
FORCEADD RES..2
R 2
(125 2225);
FORCEPROP 1 LAST LOCATION R2L4
J 2
(80 2350);
DISPLAY 0.617021 (80 2350);
PAINT AQUA (80 2350);
FORCEPROP 1 LAST PART_NUMBER G21796-001
J 2
(85 2100);
DISPLAY 0.617021 (85 2100);
PAINT BLUE (85 2100);
FORCEPROP 1 LAST VALUE 2.0K
J 2
(80 2300);
DISPLAY 0.617021 (80 2300);
PAINT SKYBLUE (80 2300);
FORCEPROP 1 LAST TOLERANCE 1%
J 2
(80 2250);
DISPLAY 0.617021 (80 2250);
PAINT SKYBLUE (80 2250);
FORCEPROP 1 LAST PACK_TYPE 0402
J 2
(85 2050);
DISPLAY 0.617021 (85 2050);
PAINT SKYBLUE (85 2050);
FORCEPROP 1 LAST MATERIAL CHIP
J 2
(85 2150);
DISPLAY 0.617021 (85 2150);
PAINT SKYBLUE (85 2150);
FORCEPROP 1 LAST WATTAGE 1/16W
J 2
(85 2200);
DISPLAY 0.617021 (85 2200);
PAINT SKYBLUE (85 2200);
FORCEPROP 1 LASTPIN (125 2125) $PN 2
J 2
(120 2135);
DISPLAY 0.617021 (120 2135);
PAINT ORANGE (120 2135);
FORCEPROP 1 LASTPIN (125 2325) $PN 1
J 2
(120 2287);
DISPLAY 0.617021 (120 2287);
PAINT ORANGE (120 2287);
FORCEPROP 0 LAST BOM_COST ST_SATA
J 0
(100 2450);
DISPLAY 1.021277 (100 2450);
PAINT ORANGE (100 2450);
DISPLAY INVISIBLE (100 2450);
FORCEPROP 2 LAST SEC_TYPE 0402
J 0
(75 2450);
DISPLAY 1.021277 (75 2450);
PAINT ORANGE (75 2450);
DISPLAY INVISIBLE (75 2450);
FORCEPROP 2 LAST CDS_LIB mstr_discrete
J 0
(125 2225);
PAINT MONO (125 2225);
DISPLAY INVISIBLE (125 2225);
FORCEPROP 2 LAST SEC 1
J 0
(75 2450);
DISPLAY 0.680851 (75 2450);
PAINT MONO (75 2450);
DISPLAY INVISIBLE (75 2450);
FORCEPROP 2 LAST CDS_LOCATION R2L4
J 2
(80 2350);
DISPLAY 0.617021 (80 2350);
PAINT AQUA (80 2350);
DISPLAY INVISIBLE (80 2350);
FORCEPROP 1 LAST PATH I18
J 2
(75 2400);
DISPLAY 0.978723 (75 2400);
PAINT WHITE (75 2400);
DISPLAY INVISIBLE (75 2400);
FORCEPROP 0 LAST ROOM ST_SATA
J 0
(100 2450);
DISPLAY 1.021277 (100 2450);
PAINT ORANGE (100 2450);
DISPLAY INVISIBLE (100 2450);
FORCEADD P3V3_STBY..1
(-200 2625);
FORCEPROP 3 LASTPIN (-200 2575) SIG_NAME P3V3_STBY\g
J 0
(-190 2585);
DISPLAY 0.659574 (-190 2585);
PAINT MONO (-190 2585);
DISPLAY INVISIBLE (-190 2585);
FORCEPROP 1 LAST VOLTAGE 3.3V
J 0
(-245 2582);
DISPLAY 0.340426 (-245 2582);
PAINT SKYBLUE (-245 2582);
DISPLAY INVISIBLE (-245 2582);
FORCEPROP 2 LAST CDS_LIB mstr_symbols
J 0
(-200 2625);
PAINT MONO (-200 2625);
DISPLAY INVISIBLE (-200 2625);
FORCEPROP 1 LAST SIZE 1B
J 0
(-155 2647);
DISPLAY 0.340426 (-155 2647);
PAINT GREEN (-155 2647);
DISPLAY INVISIBLE (-155 2647);
FORCEPROP 1 LAST BODY_TYPE PLUMBING
J 0
(-245 2582);
DISPLAY 0.340426 (-245 2582);
PAINT GREEN (-245 2582);
DISPLAY INVISIBLE (-245 2582);
FORCEPROP 1 LAST PATH I19
J 0
(-155 2627);
DISPLAY 0.340426 (-155 2627);
PAINT GREEN (-155 2627);
DISPLAY INVISIBLE (-155 2627);
FORCEPROP 1 LAST HDL_POWER P3V3_STBY
J 0
(-500 2500);
DISPLAY 0.872340 (-500 2500);
PAINT ORANGE (-500 2500);
DISPLAY INVISIBLE (-500 2500);
FORCEADD RES..2
R 2
(-200 4125);
FORCEPROP 1 LAST LOCATION R2L12
J 2
(-245 4250);
DISPLAY 0.617021 (-245 4250);
PAINT AQUA (-245 4250);
FORCEPROP 1 LAST PART_NUMBER G21796-001
J 2
(-240 4000);
DISPLAY 0.617021 (-240 4000);
PAINT BLUE (-240 4000);
FORCEPROP 1 LAST VALUE 2.0K
J 2
(-245 4200);
DISPLAY 0.617021 (-245 4200);
PAINT SKYBLUE (-245 4200);
FORCEPROP 1 LAST TOLERANCE 1%
J 2
(-245 4150);
DISPLAY 0.617021 (-245 4150);
PAINT SKYBLUE (-245 4150);
FORCEPROP 1 LAST PACK_TYPE 0402
J 2
(-240 3950);
DISPLAY 0.617021 (-240 3950);
PAINT SKYBLUE (-240 3950);
FORCEPROP 1 LAST MATERIAL CHIP
J 2
(-240 4050);
DISPLAY 0.617021 (-240 4050);
PAINT SKYBLUE (-240 4050);
FORCEPROP 1 LAST WATTAGE 1/16W
J 2
(-240 4100);
DISPLAY 0.617021 (-240 4100);
PAINT SKYBLUE (-240 4100);
FORCEPROP 1 LASTPIN (-200 4025) $PN 2
J 2
(-205 4035);
DISPLAY 0.617021 (-205 4035);
PAINT ORANGE (-205 4035);
FORCEPROP 1 LASTPIN (-200 4225) $PN 1
J 2
(-205 4187);
DISPLAY 0.617021 (-205 4187);
PAINT ORANGE (-205 4187);
FORCEPROP 0 LAST BOM_COST ST_SATA
J 0
(-225 4350);
DISPLAY 1.021277 (-225 4350);
PAINT ORANGE (-225 4350);
DISPLAY INVISIBLE (-225 4350);
FORCEPROP 2 LAST SEC_TYPE 0402
J 0
(-250 4350);
DISPLAY 1.021277 (-250 4350);
PAINT ORANGE (-250 4350);
DISPLAY INVISIBLE (-250 4350);
FORCEPROP 2 LAST CDS_LIB mstr_discrete
J 0
(-200 4125);
PAINT MONO (-200 4125);
DISPLAY INVISIBLE (-200 4125);
FORCEPROP 2 LAST SEC 1
J 0
(-250 4350);
DISPLAY 0.680851 (-250 4350);
PAINT MONO (-250 4350);
DISPLAY INVISIBLE (-250 4350);
FORCEPROP 2 LAST CDS_LOCATION R2L12
J 2
(-245 4250);
DISPLAY 0.617021 (-245 4250);
PAINT AQUA (-245 4250);
DISPLAY INVISIBLE (-245 4250);
FORCEPROP 1 LAST PATH I2
J 2
(-250 4300);
DISPLAY 0.978723 (-250 4300);
PAINT WHITE (-250 4300);
DISPLAY INVISIBLE (-250 4300);
FORCEPROP 0 LAST ROOM ST_SATA
J 0
(-225 4350);
DISPLAY 1.021277 (-225 4350);
PAINT ORANGE (-225 4350);
DISPLAY INVISIBLE (-225 4350);
FORCEADD RES..2
R 2
(-200 2225);
FORCEPROP 1 LAST LOCATION R2L5
J 2
(-245 2350);
DISPLAY 0.617021 (-245 2350);
PAINT AQUA (-245 2350);
FORCEPROP 1 LAST PART_NUMBER G21796-001
J 2
(-240 2100);
DISPLAY 0.617021 (-240 2100);
PAINT BLUE (-240 2100);
FORCEPROP 1 LAST VALUE 2.0K
J 2
(-245 2300);
DISPLAY 0.617021 (-245 2300);
PAINT SKYBLUE (-245 2300);
FORCEPROP 1 LAST TOLERANCE 1%
J 2
(-245 2250);
DISPLAY 0.617021 (-245 2250);
PAINT SKYBLUE (-245 2250);
FORCEPROP 1 LAST PACK_TYPE 0402
J 2
(-240 2050);
DISPLAY 0.617021 (-240 2050);
PAINT SKYBLUE (-240 2050);
FORCEPROP 1 LAST MATERIAL CHIP
J 2
(-240 2150);
DISPLAY 0.617021 (-240 2150);
PAINT SKYBLUE (-240 2150);
FORCEPROP 1 LAST WATTAGE 1/16W
J 2
(-240 2200);
DISPLAY 0.617021 (-240 2200);
PAINT SKYBLUE (-240 2200);
FORCEPROP 1 LASTPIN (-200 2125) $PN 2
J 2
(-205 2135);
DISPLAY 0.617021 (-205 2135);
PAINT ORANGE (-205 2135);
FORCEPROP 1 LASTPIN (-200 2325) $PN 1
J 2
(-205 2287);
DISPLAY 0.617021 (-205 2287);
PAINT ORANGE (-205 2287);
FORCEPROP 2 LAST CDS_LIB mstr_discrete
J 0
(-200 2225);
PAINT MONO (-200 2225);
DISPLAY INVISIBLE (-200 2225);
FORCEPROP 2 LAST SEC_TYPE 0402
J 0
(-250 2450);
DISPLAY 1.021277 (-250 2450);
PAINT ORANGE (-250 2450);
DISPLAY INVISIBLE (-250 2450);
FORCEPROP 0 LAST BOM_COST ST_SATA
J 0
(-225 2450);
DISPLAY 1.021277 (-225 2450);
PAINT ORANGE (-225 2450);
DISPLAY INVISIBLE (-225 2450);
FORCEPROP 2 LAST SEC 1
J 0
(-250 2450);
DISPLAY 0.680851 (-250 2450);
PAINT MONO (-250 2450);
DISPLAY INVISIBLE (-250 2450);
FORCEPROP 2 LAST CDS_LOCATION R2L5
J 2
(-245 2350);
DISPLAY 0.617021 (-245 2350);
PAINT AQUA (-245 2350);
DISPLAY INVISIBLE (-245 2350);
FORCEPROP 1 LAST PATH I20
J 2
(-250 2400);
DISPLAY 0.978723 (-250 2400);
PAINT WHITE (-250 2400);
DISPLAY INVISIBLE (-250 2400);
FORCEPROP 0 LAST ROOM ST_SATA
J 0
(-225 2450);
DISPLAY 1.021277 (-225 2450);
PAINT ORANGE (-225 2450);
DISPLAY INVISIBLE (-225 2450);
FORCEADD RES..1
(-800 1675);
FORCEPROP 1 LAST LOCATION R8B29
J 0
(-825 1725);
DISPLAY 0.617021 (-825 1725);
PAINT AQUA (-825 1725);
FORCEPROP 1 LAST PART_NUMBER G21796-047
J 0
(-525 1625);
DISPLAY 0.617021 (-525 1625);
PAINT BLUE (-525 1625);
FORCEPROP 1 LAST VALUE 49.9
J 2
(-825 1625);
DISPLAY 0.617021 (-825 1625);
PAINT SKYBLUE (-825 1625);
FORCEPROP 1 LAST TOLERANCE 1%
J 0
(-800 1625);
DISPLAY 0.617021 (-800 1625);
PAINT SKYBLUE (-800 1625);
FORCEPROP 1 LAST PACK_TYPE 0402
J 0
(-625 1625);
DISPLAY 0.617021 (-625 1625);
PAINT SKYBLUE (-625 1625);
FORCEPROP 1 LAST MATERIAL CHIP
J 0
(-725 1625);
DISPLAY 0.617021 (-725 1625);
PAINT SKYBLUE (-725 1625);
FORCEPROP 1 LAST WATTAGE 1/16W
J 2
(-925 1625);
DISPLAY 0.617021 (-925 1625);
PAINT SKYBLUE (-925 1625);
FORCEPROP 1 LASTPIN (-700 1675) $PN 2
J 0
(-738 1687);
DISPLAY 0.617021 (-738 1687);
PAINT ORANGE (-738 1687);
FORCEPROP 1 LASTPIN (-900 1675) $PN 1
J 0
(-888 1687);
DISPLAY 0.617021 (-888 1687);
PAINT ORANGE (-888 1687);
FORCEPROP 0 LAST BOM_COST ST_SATA
J 0
(-800 1875);
DISPLAY 1.021277 (-800 1875);
PAINT ORANGE (-800 1875);
DISPLAY INVISIBLE (-800 1875);
FORCEPROP 2 LAST SEC_TYPE 0402
J 0
(-850 1875);
DISPLAY 1.021277 (-850 1875);
PAINT ORANGE (-850 1875);
DISPLAY INVISIBLE (-850 1875);
FORCEPROP 2 LAST CDS_LIB mstr_discrete
J 0
(-800 1675);
PAINT MONO (-800 1675);
DISPLAY INVISIBLE (-800 1675);
FORCEPROP 2 LAST SEC 1
J 0
(-850 1875);
DISPLAY 0.680851 (-850 1875);
PAINT MONO (-850 1875);
DISPLAY INVISIBLE (-850 1875);
FORCEPROP 2 LAST CDS_LOCATION R8B29
J 0
(-825 1725);
DISPLAY 0.617021 (-825 1725);
PAINT AQUA (-825 1725);
DISPLAY INVISIBLE (-825 1725);
FORCEPROP 1 LAST PATH I21
J 0
(-850 1825);
DISPLAY 0.978723 (-850 1825);
PAINT WHITE (-850 1825);
DISPLAY INVISIBLE (-850 1825);
FORCEPROP 0 LAST ROOM ST_SATA
J 0
(-850 1875);
DISPLAY 1.021277 (-850 1875);
PAINT ORANGE (-850 1875);
DISPLAY INVISIBLE (-850 1875);
FORCEADD RES..1
(-800 1825);
FORCEPROP 1 LAST LOCATION R2N19
J 0
(-825 1875);
DISPLAY 0.617021 (-825 1875);
PAINT AQUA (-825 1875);
FORCEPROP 1 LAST PART_NUMBER G21796-047
J 0
(-525 1775);
DISPLAY 0.617021 (-525 1775);
PAINT BLUE (-525 1775);
FORCEPROP 1 LAST VALUE 49.9
J 2
(-825 1775);
DISPLAY 0.617021 (-825 1775);
PAINT SKYBLUE (-825 1775);
FORCEPROP 1 LAST TOLERANCE 1%
J 0
(-800 1775);
DISPLAY 0.617021 (-800 1775);
PAINT SKYBLUE (-800 1775);
FORCEPROP 1 LAST PACK_TYPE 0402
J 0
(-625 1775);
DISPLAY 0.617021 (-625 1775);
PAINT SKYBLUE (-625 1775);
FORCEPROP 1 LAST MATERIAL CHIP
J 0
(-725 1775);
DISPLAY 0.617021 (-725 1775);
PAINT SKYBLUE (-725 1775);
FORCEPROP 1 LAST WATTAGE 1/16W
J 2
(-925 1775);
DISPLAY 0.617021 (-925 1775);
PAINT SKYBLUE (-925 1775);
FORCEPROP 1 LASTPIN (-700 1825) $PN 2
J 0
(-738 1837);
DISPLAY 0.617021 (-738 1837);
PAINT ORANGE (-738 1837);
FORCEPROP 1 LASTPIN (-900 1825) $PN 1
J 0
(-888 1837);
DISPLAY 0.617021 (-888 1837);
PAINT ORANGE (-888 1837);
FORCEPROP 0 LAST BOM_COST ST_SATA
J 0
(-800 2025);
DISPLAY 1.021277 (-800 2025);
PAINT ORANGE (-800 2025);
DISPLAY INVISIBLE (-800 2025);
FORCEPROP 2 LAST SEC_TYPE 0402
J 0
(-850 2025);
DISPLAY 1.021277 (-850 2025);
PAINT ORANGE (-850 2025);
DISPLAY INVISIBLE (-850 2025);
FORCEPROP 2 LAST CDS_LIB mstr_discrete
J 0
(-800 1825);
PAINT MONO (-800 1825);
DISPLAY INVISIBLE (-800 1825);
FORCEPROP 2 LAST SEC 1
J 0
(-850 2025);
DISPLAY 0.680851 (-850 2025);
PAINT MONO (-850 2025);
DISPLAY INVISIBLE (-850 2025);
FORCEPROP 2 LAST CDS_LOCATION R2N19
J 0
(-825 1875);
DISPLAY 0.617021 (-825 1875);
PAINT AQUA (-825 1875);
DISPLAY INVISIBLE (-825 1875);
FORCEPROP 1 LAST PATH I22
J 0
(-850 1975);
DISPLAY 0.978723 (-850 1975);
PAINT WHITE (-850 1975);
DISPLAY INVISIBLE (-850 1975);
FORCEPROP 0 LAST ROOM ST_SATA
J 0
(-850 2025);
DISPLAY 1.021277 (-850 2025);
PAINT ORANGE (-850 2025);
DISPLAY INVISIBLE (-850 2025);
FORCEADD RES..1
(-800 1525);
FORCEPROP 1 LAST LOCATION R2N22
J 0
(-825 1575);
DISPLAY 0.617021 (-825 1575);
PAINT AQUA (-825 1575);
FORCEPROP 1 LAST PART_NUMBER G21796-047
J 0
(-525 1475);
DISPLAY 0.617021 (-525 1475);
PAINT BLUE (-525 1475);
FORCEPROP 1 LAST VALUE 49.9
J 2
(-825 1475);
DISPLAY 0.617021 (-825 1475);
PAINT SKYBLUE (-825 1475);
FORCEPROP 1 LAST TOLERANCE 1%
J 0
(-800 1475);
DISPLAY 0.617021 (-800 1475);
PAINT SKYBLUE (-800 1475);
FORCEPROP 1 LAST PACK_TYPE 0402
J 0
(-625 1475);
DISPLAY 0.617021 (-625 1475);
PAINT SKYBLUE (-625 1475);
FORCEPROP 1 LAST MATERIAL CHIP
J 0
(-725 1475);
DISPLAY 0.617021 (-725 1475);
PAINT SKYBLUE (-725 1475);
FORCEPROP 1 LAST WATTAGE 1/16W
J 2
(-925 1475);
DISPLAY 0.617021 (-925 1475);
PAINT SKYBLUE (-925 1475);
FORCEPROP 1 LASTPIN (-700 1525) $PN 2
J 0
(-738 1537);
DISPLAY 0.617021 (-738 1537);
PAINT ORANGE (-738 1537);
FORCEPROP 1 LASTPIN (-900 1525) $PN 1
J 0
(-888 1537);
DISPLAY 0.617021 (-888 1537);
PAINT ORANGE (-888 1537);
FORCEPROP 0 LAST BOM_COST ST_SATA
J 0
(-800 1725);
DISPLAY 1.021277 (-800 1725);
PAINT ORANGE (-800 1725);
DISPLAY INVISIBLE (-800 1725);
FORCEPROP 2 LAST SEC_TYPE 0402
J 0
(-850 1725);
DISPLAY 1.021277 (-850 1725);
PAINT ORANGE (-850 1725);
DISPLAY INVISIBLE (-850 1725);
FORCEPROP 2 LAST CDS_LIB mstr_discrete
J 0
(-800 1525);
PAINT MONO (-800 1525);
DISPLAY INVISIBLE (-800 1525);
FORCEPROP 2 LAST SEC 1
J 0
(-850 1725);
DISPLAY 0.680851 (-850 1725);
PAINT MONO (-850 1725);
DISPLAY INVISIBLE (-850 1725);
FORCEPROP 2 LAST CDS_LOCATION R2N22
J 0
(-825 1575);
DISPLAY 0.617021 (-825 1575);
PAINT AQUA (-825 1575);
DISPLAY INVISIBLE (-825 1575);
FORCEPROP 1 LAST PATH I23
J 0
(-850 1675);
DISPLAY 0.978723 (-850 1675);
PAINT WHITE (-850 1675);
DISPLAY INVISIBLE (-850 1675);
FORCEPROP 0 LAST ROOM ST_SATA
J 0
(-850 1725);
DISPLAY 1.021277 (-850 1725);
PAINT ORANGE (-850 1725);
DISPLAY INVISIBLE (-850 1725);
FORCEADD OFFPAGE..1
(-1700 1675);
FORCEPROP 2 LAST $XR0 119 
J 0
(-1952 1675);
DISPLAY 0.638298 (-1952 1675);
PAINT MONO (-1952 1675);
FORCEPROP 2 LAST CDS_LIB mstr_standard
J 0
(-1700 1675);
PAINT MONO (-1700 1675);
DISPLAY INVISIBLE (-1700 1675);
FORCEPROP 1 LAST OFFPAGE TRUE
J 0
(-1375 1550);
DISPLAY 0.872340 (-1375 1550);
PAINT GREEN (-1375 1550);
DISPLAY INVISIBLE (-1375 1550);
FORCEPROP 1 LAST COMMENT_BODY TRUE
J 0
(-1575 1575);
DISPLAY 0.872340 (-1575 1575);
PAINT GREEN (-1575 1575);
DISPLAY INVISIBLE (-1575 1575);
FORCEPROP 2 LAST PATH I24
J 0
(-1650 1750);
DISPLAY 1.021277 (-1650 1750);
PAINT ORANGE (-1650 1750);
DISPLAY INVISIBLE (-1650 1750);
FORCEADD OFFPAGE..1
(-1700 1825);
FORCEPROP 2 LAST $XR0 120 
J 0
(-1952 1825);
DISPLAY 0.638298 (-1952 1825);
PAINT MONO (-1952 1825);
FORCEPROP 2 LAST CDS_LIB mstr_standard
J 0
(-1700 1825);
PAINT MONO (-1700 1825);
DISPLAY INVISIBLE (-1700 1825);
FORCEPROP 1 LAST OFFPAGE TRUE
J 0
(-1375 1700);
DISPLAY 0.872340 (-1375 1700);
PAINT GREEN (-1375 1700);
DISPLAY INVISIBLE (-1375 1700);
FORCEPROP 1 LAST COMMENT_BODY TRUE
J 0
(-1575 1725);
DISPLAY 0.872340 (-1575 1725);
PAINT GREEN (-1575 1725);
DISPLAY INVISIBLE (-1575 1725);
FORCEPROP 2 LAST PATH I25
J 0
(-1650 1900);
DISPLAY 1.021277 (-1650 1900);
PAINT ORANGE (-1650 1900);
DISPLAY INVISIBLE (-1650 1900);
FORCEADD OFFPAGE..1
(-1700 1525);
FORCEPROP 2 LAST $XR0 120 
J 0
(-1952 1525);
DISPLAY 0.638298 (-1952 1525);
PAINT MONO (-1952 1525);
FORCEPROP 2 LAST CDS_LIB mstr_standard
J 0
(-1700 1525);
PAINT MONO (-1700 1525);
DISPLAY INVISIBLE (-1700 1525);
FORCEPROP 1 LAST OFFPAGE TRUE
J 0
(-1375 1400);
DISPLAY 0.872340 (-1375 1400);
PAINT GREEN (-1375 1400);
DISPLAY INVISIBLE (-1375 1400);
FORCEPROP 1 LAST COMMENT_BODY TRUE
J 0
(-1575 1425);
DISPLAY 0.872340 (-1575 1425);
PAINT GREEN (-1575 1425);
DISPLAY INVISIBLE (-1575 1425);
FORCEPROP 2 LAST PATH I26
J 0
(-1650 1600);
DISPLAY 1.021277 (-1650 1600);
PAINT ORANGE (-1650 1600);
DISPLAY INVISIBLE (-1650 1600);
FORCEADD OFFPAGE..1
(-1700 3725);
FORCEPROP 2 LAST $XR0 120 
J 0
(-1952 3725);
DISPLAY 0.638298 (-1952 3725);
PAINT MONO (-1952 3725);
FORCEPROP 2 LAST CDS_LIB mstr_standard
J 0
(-1700 3725);
PAINT MONO (-1700 3725);
DISPLAY INVISIBLE (-1700 3725);
FORCEPROP 1 LAST OFFPAGE TRUE
J 0
(-1375 3600);
DISPLAY 0.872340 (-1375 3600);
PAINT GREEN (-1375 3600);
DISPLAY INVISIBLE (-1375 3600);
FORCEPROP 1 LAST COMMENT_BODY TRUE
J 0
(-1575 3625);
DISPLAY 0.872340 (-1575 3625);
PAINT GREEN (-1575 3625);
DISPLAY INVISIBLE (-1575 3625);
FORCEPROP 2 LAST PATH I3
J 0
(-1650 3800);
DISPLAY 1.021277 (-1650 3800);
PAINT ORANGE (-1650 3800);
DISPLAY INVISIBLE (-1650 3800);
FORCEADD OFFPAGE..2
(1450 3725);
FORCEPROP 2 LAST $XR0 173 
J 0
(1639 3725);
DISPLAY 0.638298 (1639 3725);
PAINT MONO (1639 3725);
FORCEPROP 2 LAST CDS_LIB mstr_standard
J 0
(1450 3725);
PAINT MONO (1450 3725);
DISPLAY INVISIBLE (1450 3725);
FORCEPROP 1 LAST OFFPAGE TRUE
J 0
(1775 3600);
DISPLAY 0.872340 (1775 3600);
PAINT GREEN (1775 3600);
DISPLAY INVISIBLE (1775 3600);
FORCEPROP 1 LAST COMMENT_BODY TRUE
J 0
(1405 3630);
DISPLAY 0.872340 (1405 3630);
PAINT GREEN (1405 3630);
DISPLAY INVISIBLE (1405 3630);
FORCEPROP 2 LAST PATH I4
J 0
(1625 3800);
DISPLAY 1.021277 (1625 3800);
PAINT ORANGE (1625 3800);
DISPLAY INVISIBLE (1625 3800);
FORCEADD P3V3_STBY..1
(-200 4525);
FORCEPROP 3 LASTPIN (-200 4475) SIG_NAME P3V3_STBY\g
J 0
(-190 4485);
DISPLAY 0.659574 (-190 4485);
PAINT MONO (-190 4485);
DISPLAY INVISIBLE (-190 4485);
FORCEPROP 1 LAST VOLTAGE 3.3V
J 0
(-245 4482);
DISPLAY 0.340426 (-245 4482);
PAINT SKYBLUE (-245 4482);
DISPLAY INVISIBLE (-245 4482);
FORCEPROP 1 LAST SIZE 1B
J 0
(-155 4547);
DISPLAY 0.340426 (-155 4547);
PAINT GREEN (-155 4547);
DISPLAY INVISIBLE (-155 4547);
FORCEPROP 2 LAST CDS_LIB mstr_symbols
J 0
(-200 4525);
PAINT MONO (-200 4525);
DISPLAY INVISIBLE (-200 4525);
FORCEPROP 1 LAST BODY_TYPE PLUMBING
J 0
(-245 4482);
DISPLAY 0.340426 (-245 4482);
PAINT GREEN (-245 4482);
DISPLAY INVISIBLE (-245 4482);
FORCEPROP 1 LAST PATH I5
J 0
(-155 4527);
DISPLAY 0.340426 (-155 4527);
PAINT GREEN (-155 4527);
DISPLAY INVISIBLE (-155 4527);
FORCEPROP 1 LAST HDL_POWER P3V3_STBY
J 0
(-500 4400);
DISPLAY 0.872340 (-500 4400);
PAINT ORANGE (-500 4400);
DISPLAY INVISIBLE (-500 4400);
FORCEADD OFFPAGE..1
(-1700 3575);
FORCEPROP 2 LAST $XR0 120 
J 0
(-1952 3575);
DISPLAY 0.638298 (-1952 3575);
PAINT MONO (-1952 3575);
FORCEPROP 2 LAST CDS_LIB mstr_standard
J 0
(-1700 3575);
PAINT MONO (-1700 3575);
DISPLAY INVISIBLE (-1700 3575);
FORCEPROP 1 LAST OFFPAGE TRUE
J 0
(-1375 3450);
DISPLAY 0.872340 (-1375 3450);
PAINT GREEN (-1375 3450);
DISPLAY INVISIBLE (-1375 3450);
FORCEPROP 1 LAST COMMENT_BODY TRUE
J 0
(-1575 3475);
DISPLAY 0.872340 (-1575 3475);
PAINT GREEN (-1575 3475);
DISPLAY INVISIBLE (-1575 3475);
FORCEPROP 2 LAST PATH I6
J 0
(-1650 3650);
DISPLAY 1.021277 (-1650 3650);
PAINT ORANGE (-1650 3650);
DISPLAY INVISIBLE (-1650 3650);
FORCEADD OFFPAGE..2
(1450 3575);
FORCEPROP 2 LAST $XR0 173 
J 0
(1639 3575);
DISPLAY 0.638298 (1639 3575);
PAINT MONO (1639 3575);
FORCEPROP 2 LAST CDS_LIB mstr_standard
J 0
(1450 3575);
PAINT MONO (1450 3575);
DISPLAY INVISIBLE (1450 3575);
FORCEPROP 1 LAST OFFPAGE TRUE
J 0
(1775 3450);
DISPLAY 0.872340 (1775 3450);
PAINT GREEN (1775 3450);
DISPLAY INVISIBLE (1775 3450);
FORCEPROP 1 LAST COMMENT_BODY TRUE
J 0
(1405 3480);
DISPLAY 0.872340 (1405 3480);
PAINT GREEN (1405 3480);
DISPLAY INVISIBLE (1405 3480);
FORCEPROP 2 LAST PATH I7
J 0
(1625 3650);
DISPLAY 1.021277 (1625 3650);
PAINT ORANGE (1625 3650);
DISPLAY INVISIBLE (1625 3650);
FORCEADD RES..1
(-800 3575);
FORCEPROP 1 LAST LOCATION R8D19
J 0
(-825 3625);
DISPLAY 0.617021 (-825 3625);
PAINT AQUA (-825 3625);
FORCEPROP 1 LAST PART_NUMBER G21796-047
J 0
(-525 3525);
DISPLAY 0.617021 (-525 3525);
PAINT BLUE (-525 3525);
FORCEPROP 1 LAST VALUE 49.9
J 2
(-825 3525);
DISPLAY 0.617021 (-825 3525);
PAINT SKYBLUE (-825 3525);
FORCEPROP 1 LAST TOLERANCE 1%
J 0
(-800 3525);
DISPLAY 0.617021 (-800 3525);
PAINT SKYBLUE (-800 3525);
FORCEPROP 1 LAST PACK_TYPE 0402
J 0
(-625 3525);
DISPLAY 0.617021 (-625 3525);
PAINT SKYBLUE (-625 3525);
FORCEPROP 1 LAST MATERIAL CHIP
J 0
(-725 3525);
DISPLAY 0.617021 (-725 3525);
PAINT SKYBLUE (-725 3525);
FORCEPROP 1 LAST WATTAGE 1/16W
J 2
(-925 3525);
DISPLAY 0.617021 (-925 3525);
PAINT SKYBLUE (-925 3525);
FORCEPROP 1 LASTPIN (-700 3575) $PN 2
J 0
(-738 3587);
DISPLAY 0.617021 (-738 3587);
PAINT ORANGE (-738 3587);
FORCEPROP 1 LASTPIN (-900 3575) $PN 1
J 0
(-888 3587);
DISPLAY 0.617021 (-888 3587);
PAINT ORANGE (-888 3587);
FORCEPROP 2 LAST CDS_LIB mstr_discrete
J 0
(-800 3575);
PAINT MONO (-800 3575);
DISPLAY INVISIBLE (-800 3575);
FORCEPROP 2 LAST SEC_TYPE 0402
J 0
(-850 3775);
DISPLAY 1.021277 (-850 3775);
PAINT ORANGE (-850 3775);
DISPLAY INVISIBLE (-850 3775);
FORCEPROP 0 LAST BOM_COST ST_SATA
J 0
(-800 3775);
DISPLAY 1.021277 (-800 3775);
PAINT ORANGE (-800 3775);
DISPLAY INVISIBLE (-800 3775);
FORCEPROP 2 LAST SEC 1
J 0
(-850 3775);
DISPLAY 0.680851 (-850 3775);
PAINT MONO (-850 3775);
DISPLAY INVISIBLE (-850 3775);
FORCEPROP 2 LAST CDS_LOCATION R8D19
J 0
(-825 3625);
DISPLAY 0.617021 (-825 3625);
PAINT AQUA (-825 3625);
DISPLAY INVISIBLE (-825 3625);
FORCEPROP 1 LAST PATH I8
J 0
(-850 3725);
DISPLAY 0.978723 (-850 3725);
PAINT WHITE (-850 3725);
DISPLAY INVISIBLE (-850 3725);
FORCEPROP 0 LAST ROOM ST_SATA
J 0
(-850 3775);
DISPLAY 1.021277 (-850 3775);
PAINT ORANGE (-850 3775);
DISPLAY INVISIBLE (-850 3775);
FORCEADD OFFPAGE..1
(-1700 3425);
FORCEPROP 2 LAST $XR0 120 
J 0
(-1952 3425);
DISPLAY 0.638298 (-1952 3425);
PAINT MONO (-1952 3425);
FORCEPROP 2 LAST CDS_LIB mstr_standard
J 0
(-1700 3425);
PAINT MONO (-1700 3425);
DISPLAY INVISIBLE (-1700 3425);
FORCEPROP 1 LAST OFFPAGE TRUE
J 0
(-1375 3300);
DISPLAY 0.872340 (-1375 3300);
PAINT GREEN (-1375 3300);
DISPLAY INVISIBLE (-1375 3300);
FORCEPROP 1 LAST COMMENT_BODY TRUE
J 0
(-1575 3325);
DISPLAY 0.872340 (-1575 3325);
PAINT GREEN (-1575 3325);
DISPLAY INVISIBLE (-1575 3325);
FORCEPROP 2 LAST PATH I9
J 0
(-1650 3500);
DISPLAY 1.021277 (-1650 3500);
PAINT ORANGE (-1650 3500);
DISPLAY INVISIBLE (-1650 3500);
FORCEADD DESIGN_NOTE..1
(975 4350);
FORCEPROP 0 LAST L1 PLACE RESISTORS CLOSE TO MINI SAS CONNECTOR
J 0
(775 4225);
DISPLAY 1.021277 (775 4225);
PAINT ORANGE (775 4225);
FORCEPROP 2 LAST CDS_LIB mstr_symbols
J 0
(975 4350);
PAINT MONO (975 4350);
DISPLAY INVISIBLE (975 4350);
FORCEPROP 1 LAST COMMENT_BODY TRUE
J 0
(1000 4450);
DISPLAY 0.978723 (1000 4450);
PAINT ORANGE (1000 4450);
DISPLAY INVISIBLE (1000 4450);
FORCEADD DESIGN_NOTE..1
(-875 1275);
FORCEPROP 0 LAST L1 PLACE RESISTORS <2 INCHES FROM PCH
J 0
(-1075 1125);
DISPLAY 1.021277 (-1075 1125);
PAINT ORANGE (-1075 1125);
FORCEPROP 2 LAST CDS_LIB mstr_symbols
J 0
(-875 1275);
PAINT MONO (-875 1275);
DISPLAY INVISIBLE (-875 1275);
FORCEPROP 1 LAST COMMENT_BODY TRUE
J 0
(-850 1375);
DISPLAY 0.978723 (-850 1375);
PAINT ORANGE (-850 1375);
DISPLAY INVISIBLE (-850 1375);
FORCEADD INTEL_CORP_BPAGE..1
(4250 200);
FORCEPROP 1 LAST CDS_CON_LAST_MODIFIED Tue Dec 01 11:52:14 2015
J 0
(2825 525);
PAINT ORANGE (2825 525);
DISPLAY INVISIBLE (2825 525);
FORCEPROP 1 LAST CUSTOM_TXT_CDS <CURRENT_DESIGN_SHEET> OF <TOTAL_DESIGN_SHEETS>
J 0
(3750 225);
PAINT GREEN (3750 225);
FORCEPROP 1 LAST CUSTOM_TXT_CDS <CON_LAST_MODIFIED>
J 0
(2325 550);
PAINT GREEN (2325 550);
FORCEPROP 2 LAST CUSTOM_TXT_CDS <XR_PAGE_TITLE>
J 0
(-3640 5450);
DISPLAY 0.638298 (-3640 5450);
PAINT PINK (-3640 5450);
DISPLAY INVISIBLE (-3640 5450);
FORCEPROP 1 LAST SCH_ADDRESS3 Santa Clara, CA 95052-8119
J 0
(275 225);
DISPLAY 0.617021 (275 225);
PAINT YELLOW (275 225);
FORCEPROP 1 LAST SCH_ADDRESS2 P.O. BOX 58119
J 0
(275 275);
DISPLAY 0.617021 (275 275);
PAINT YELLOW (275 275);
FORCEPROP 1 LAST SCH_ADDRESS1 2200 Mission College Blvd.
J 0
(275 325);
DISPLAY 0.617021 (275 325);
PAINT YELLOW (275 325);
FORCEPROP 1 LAST SCH_TITLE SATA SGPIO CONNECTORS
J 0
(-3700 250);
DISPLAY 1.212766 (-3700 250);
PAINT YELLOW (-3700 250);
FORCEPROP 1 LAST SCH_NUMBER H4694802
J 0
(2950 350);
DISPLAY 1.212766 (2950 350);
PAINT YELLOW (2950 350);
FORCEPROP 1 LAST SCH_DEPT BESD
J 1
(-200 300);
DISPLAY 1.212766 (-200 300);
PAINT YELLOW (-200 300);
FORCEPROP 1 LAST SCH_REV 2.420
J 0
(4000 350);
DISPLAY 0.978723 (4000 350);
PAINT YELLOW (4000 350);
FORCEPROP 2 LAST CDS_LIB mstr_symbols
J 0
(4250 200);
PAINT MONO (4250 200);
DISPLAY INVISIBLE (4250 200);
FORCEPROP 2 LAST PAGE_BORDER TRUE
J 0
(-3640 5450);
DISPLAY 0.638298 (-3640 5450);
PAINT PINK (-3640 5450);
DISPLAY INVISIBLE (-3640 5450);
FORCEPROP 1 LAST COMMENT_BODY TRUE
J 0
(4262 212);
DISPLAY 0.468085 (4262 212);
PAINT PEACH (4262 212);
DISPLAY INVISIBLE (4262 212);
FORCEPROP 2 LAST CDS_XR_PAGE_TITLE CR-178 : @BASEBOARD_FAB2_LIB.BASEBOARD_FAB2(SCH_1):PAGE178
J 0
(-3640 5450);
DISPLAY 0.638298 (-3640 5450);
PAINT PINK (-3640 5450);
DISPLAY INVISIBLE (-3640 5450);
FORCEADD DESIGN_NOTE..1
(950 2450);
FORCEPROP 0 LAST L1 PLACE RESISTORS CLOSE TO MINI SAS CONNECTOR
J 0
(750 2325);
DISPLAY 1.021277 (750 2325);
PAINT ORANGE (750 2325);
FORCEPROP 2 LAST CDS_LIB mstr_symbols
J 0
(950 2450);
PAINT MONO (950 2450);
DISPLAY INVISIBLE (950 2450);
FORCEPROP 1 LAST COMMENT_BODY TRUE
J 0
(975 2550);
DISPLAY 0.978723 (975 2550);
PAINT ORANGE (975 2550);
DISPLAY INVISIBLE (975 2550);
FORCEADD DESIGN_NOTE..1
(-875 3175);
FORCEPROP 0 LAST L1 PLACE RESISTORS <2 INCHES FROM PCH
J 0
(-1075 3025);
DISPLAY 1.021277 (-1075 3025);
PAINT ORANGE (-1075 3025);
FORCEPROP 2 LAST CDS_LIB mstr_symbols
J 0
(-875 3175);
PAINT MONO (-875 3175);
DISPLAY INVISIBLE (-875 3175);
FORCEPROP 1 LAST COMMENT_BODY TRUE
J 0
(-850 3275);
DISPLAY 0.978723 (-850 3275);
PAINT ORANGE (-850 3275);
DISPLAY INVISIBLE (-850 3275);
WIRE 16 -1 (475 2325)(475 2450);
WIRE 16 -1 (475 2450)(125 2450);
WIRE 16 -1 (125 2325)(125 2450);
WIRE 16 -1 (125 2450)(-200 2450);
WIRE 16 -1 (-200 2325)(-200 2450);
WIRE 16 -1 (-200 2450)(-200 2575);
WIRE 16 -1 (575 4225)(575 4350);
WIRE 16 -1 (575 4350)(225 4350);
WIRE 16 -1 (225 4225)(225 4350);
WIRE 16 -1 (225 4350)(-200 4350);
WIRE 16 -1 (-200 4225)(-200 4350);
WIRE 16 -1 (-200 4350)(-200 4475);
WIRE 16 273 (-525 1975)(-525 1375);
WIRE 16 273 (-525 1975)(-1075 1975);
WIRE 16 273 (-525 1375)(-1075 1375);
WIRE 16 273 (-1075 1375)(-1075 1975);
WIRE 16 -1 (-900 1675)(-1650 1675);
FORCEPROP 2 LAST SIG_NAME SGPIO_PCH_SSATA_DOUT0
J 0
(-1610 1685);
DISPLAY 0.617021 (-1610 1685);
PAINT ORANGE (-1610 1685);
WIRE 16 -1 (-900 1825)(-1650 1825);
FORCEPROP 2 LAST SIG_NAME SGPIO_PCH_SSATA_LOAD
J 0
(-1610 1835);
DISPLAY 0.617021 (-1610 1835);
PAINT ORANGE (-1610 1835);
WIRE 16 -1 (-900 1525)(-1650 1525);
FORCEPROP 2 LAST SIG_NAME SGPIO_PCH_SSATA_CLOCK
J 0
(-1610 1535);
DISPLAY 0.617021 (-1610 1535);
PAINT ORANGE (-1610 1535);
WIRE 16 273 (-550 3875)(-550 3275);
WIRE 16 273 (-550 3875)(-1100 3875);
WIRE 16 273 (-550 3275)(-1100 3275);
WIRE 16 273 (-1100 3275)(-1100 3875);
WIRE 16 -1 (-900 3725)(-1650 3725);
FORCEPROP 2 LAST SIG_NAME SGPIO_PCH_SATA_LOAD
J 0
(-1610 3735);
DISPLAY 0.617021 (-1610 3735);
PAINT ORANGE (-1610 3735);
WIRE 16 -1 (-900 3575)(-1650 3575);
FORCEPROP 2 LAST SIG_NAME SGPIO_PCH_SATA_DOUT0
J 0
(-1610 3585);
DISPLAY 0.617021 (-1610 3585);
PAINT ORANGE (-1610 3585);
WIRE 16 -1 (-900 3425)(-1650 3425);
FORCEPROP 2 LAST SIG_NAME SGPIO_PCH_SATA_CLOCK
J 0
(-1610 3435);
DISPLAY 0.617021 (-1610 3435);
PAINT ORANGE (-1610 3435);
WIRE 16 273 (650 2500)(650 1975);
WIRE 16 273 (650 2500)(-500 2500);
WIRE 16 273 (650 1975)(-500 1975);
WIRE 16 273 (-500 1975)(-500 2500);
WIRE 16 273 (675 4400)(675 3875);
WIRE 16 273 (675 4400)(-475 4400);
WIRE 16 273 (675 3875)(-475 3875);
WIRE 16 273 (-475 3875)(-475 4400);
WIRE 16 -1 (-200 2125)(-200 1825);
WIRE 16 -1 (1400 1825)(-200 1825);
FORCEPROP 2 LAST SIG_NAME SGPIO_PCH_SSATA_LOAD_R
J 0
(715 1835);
DISPLAY 0.617021 (715 1835);
PAINT ORANGE (715 1835);
WIRE 16 -1 (-700 1825)(-200 1825);
WIRE 16 -1 (-200 4025)(-200 3725);
WIRE 16 -1 (1400 3725)(-200 3725);
FORCEPROP 2 LAST SIG_NAME SGPIO_PCH_SATA_LOAD_R
J 0
(740 3735);
DISPLAY 0.617021 (740 3735);
PAINT ORANGE (740 3735);
WIRE 16 -1 (-700 3725)(-200 3725);
WIRE 16 -1 (125 2125)(125 1675);
WIRE 16 -1 (1400 1675)(125 1675);
FORCEPROP 2 LAST SIG_NAME SGPIO_PCH_SSATA_DOUT0_R
J 0
(715 1685);
DISPLAY 0.617021 (715 1685);
PAINT ORANGE (715 1685);
WIRE 16 -1 (125 1675)(-700 1675);
WIRE 16 -1 (1400 1525)(475 1525);
FORCEPROP 2 LAST SIG_NAME SGPIO_PCH_SSATA_CLOCK_R
J 0
(715 1535);
DISPLAY 0.617021 (715 1535);
PAINT ORANGE (715 1535);
WIRE 16 -1 (475 2125)(475 1525);
WIRE 16 -1 (-700 1525)(475 1525);
WIRE 16 -1 (575 4025)(575 3425);
WIRE 16 -1 (1400 3425)(575 3425);
FORCEPROP 2 LAST SIG_NAME SGPIO_PCH_SATA_CLOCK_R
J 0
(740 3435);
DISPLAY 0.617021 (740 3435);
PAINT ORANGE (740 3435);
WIRE 16 -1 (-700 3425)(575 3425);
WIRE 16 -1 (1400 3575)(225 3575);
FORCEPROP 2 LAST SIG_NAME SGPIO_PCH_SATA_DOUT0_R
J 0
(740 3585);
DISPLAY 0.617021 (740 3585);
PAINT ORANGE (740 3585);
WIRE 16 -1 (225 4025)(225 3575);
WIRE 16 -1 (225 3575)(-700 3575);
DOT 1 (575 3425);
DOT 1 (125 1675);
DOT 1 (225 4350);
DOT 1 (-200 4350);
DOT 1 (125 2450);
DOT 1 (475 1525);
DOT 1 (-200 3725);
DOT 1 (-200 1825);
DOT 1 (-200 2450);
DOT 1 (225 3575);
FORCENOTE
BOM_COST=ST_SATA
(-3600 450) 0;
DISPLAY LEFT (-3600 450);
DISPLAY 1.382979 (-3600 450);
PAINT PURPLE (-3600 450);
FORCENOTE
ROOM=ST_SATA
(-3600 575) 0;
DISPLAY LEFT (-3600 575);
DISPLAY 1.382979 (-3600 575);
PAINT PURPLE (-3600 575);
FORCENOTE
X8 MINI-SAS VERTICAL PCH PCIE_UP
(-125 4700) 0;
DISPLAY LEFT (-125 4700);
DISPLAY 1.021277 (-125 4700);
PAINT PURPLE (-125 4700);
FORCENOTE
X4 SSATA DOWN CONN
(-75 2775) 0;
DISPLAY LEFT (-75 2775);
DISPLAY 1.021277 (-75 2775);
PAINT PURPLE (-75 2775);
QUIT
